# S9S_MB_2U (Grand Teton) — schematic netlist excerpt (pin names and nets, part order shuffled) for the footprints in the layout excerpt that follows; sources: Cadence DE-HDL packaged netlist, KiCad conversion of 03242023_DA0F0TMBIJ0_F0T_Motherboard_J_brd_V01_OCP.brd

R619  Q_RES  10K 1% CHIP  pkg 0402LF  page 199 : A = P3V3_AUX ; B = FM_LT_KEY_DOWNGRADE_N
PR3847  Q_RES  14.3K 1% CHIP  pkg 0402LF  page 163 : A = P12V_OCP_ISET_2 ; B = GND

(kicad_pcb
	(version 20260206)
	(generator "pcbnew")
	(generator_version "10.0")
	(general
		(thickness 1.6)
		(legacy_teardrops no)
	)
	(paper "A4")
	(title_block
		(title "03242023_DA0F0TMBIJ0_F0T_Motherboard_J_brd_V01_OCP.brd")
		(comment 1 "Grand Teton / footprints 3990-3991 of 6105")
	)
	(layers
		(0 "F.Cu" signal "TOP")
		(4 "In1.Cu" signal "GND")
		(6 "In2.Cu" signal "IN1")
		(8 "In3.Cu" signal "GND1")
		(10 "In4.Cu" signal "IN2")
		(12 "In5.Cu" signal "GND2")
		(14 "In6.Cu" signal "IN3")
		(16 "In7.Cu" signal "GND3")
		(18 "In8.Cu" signal "VCC")
		(20 "In9.Cu" signal "VCC1")
		(22 "In10.Cu" signal "GND4")
		(24 "In11.Cu" signal "IN4")
		(26 "In12.Cu" signal "GND5")
		(28 "In13.Cu" signal "IN5")
		(30 "In14.Cu" signal "GND6")
		(32 "In15.Cu" signal "IN6")
		(34 "In16.Cu" signal "GND7")
		(2 "B.Cu" signal "BOTTOM")
		(9 "F.Adhes" user "F.Adhesive")
		(11 "B.Adhes" user "B.Adhesive")
		(13 "F.Paste" user "Package Geometry/Pastemask Top")
		(15 "B.Paste" user "Package Geometry/Pastemask Bottom")
		(5 "F.SilkS" user "Ref Des/Silkscreen Top")
		(7 "B.SilkS" user "Ref Des/Silkscreen Bottom")
		(1 "F.Mask" user "Board Geometry/Soldermask Top")
		(3 "B.Mask" user "Board Geometry/Soldermask Bottom")
		(17 "Dwgs.User" user "User.Drawings")
		(19 "Cmts.User" user "User.Comments")
		(21 "Eco1.User" user "User.Eco1")
		(23 "Eco2.User" user "User.Eco2")
		(25 "Edge.Cuts" user "Board Geometry/Outline")
		(27 "Margin" user)
		(31 "F.CrtYd" user "Package Geometry/Place Bound Top")
		(29 "B.CrtYd" user "Package Geometry/Place Bound Bottom")
		(35 "F.Fab" user "Ref Des/Assembly Top")
		(33 "B.Fab" user "Ref Des/Assembly Bottom")
	)
	(footprint ""
		(layer "F.Cu")
		(at 320.190622 -57.267348)
		(property "Reference" "R619"
			(at 0 0 0)
			(layer "F.SilkS")
			(hide yes)
			(effects
				(font
					(size 1.27 1.27)
				)
			)
		)
		(property "Value" ""
			(at 0 0 0)
			(layer "F.Fab")
			(effects
				(font
					(size 1.27 1.27)
				)
			)
		)
		(duplicate_pad_numbers_are_jumpers no)
		(fp_line
			(start -0.7874 -0.4064)
			(end 0.7874 -0.4064)
			(stroke
				(width 0.1524)
				(type default)
			)
			(layer "F.SilkS")
		)
		(fp_line
			(start -0.7874 0.4064)
			(end -0.7874 -0.4064)
			(stroke
				(width 0.1524)
				(type default)
			)
			(layer "F.SilkS")
		)
		(fp_line
			(start 0.7874 -0.4064)
			(end 0.7874 0.4064)
			(stroke
				(width 0.1524)
				(type default)
			)
			(layer "F.SilkS")
		)
		(fp_line
			(start 0.7874 0.4064)
			(end -0.7874 0.4064)
			(stroke
				(width 0.1524)
				(type default)
			)
			(layer "F.SilkS")
		)
		(fp_line
			(start -0.67945 -0.305054)
			(end -0.12065 -0.305054)
			(stroke
				(width 0.1)
				(type default)
			)
			(layer "F.Fab")
		)
		(fp_line
			(start -0.67945 0.3048)
			(end -0.67945 -0.305054)
			(stroke
				(width 0.1)
				(type default)
			)
			(layer "F.Fab")
		)
		(fp_line
			(start -0.12065 -0.305054)
			(end -0.12065 -0.2794)
			(stroke
				(width 0.1)
				(type default)
			)
			(layer "F.Fab")
		)
		(fp_line
			(start -0.12065 -0.2794)
			(end 0.12065 -0.2794)
			(stroke
				(width 0.1)
				(type default)
			)
			(layer "F.Fab")
		)
		(fp_line
			(start -0.12065 0.2794)
			(end -0.12065 0.3048)
			(stroke
				(width 0.1)
				(type default)
			)
			(layer "F.Fab")
		)
		(fp_line
			(start -0.12065 0.3048)
			(end -0.67945 0.3048)
			(stroke
				(width 0.1)
				(type default)
			)
			(layer "F.Fab")
		)
		(fp_line
			(start 0.120396 0.2794)
			(end -0.12065 0.2794)
			(stroke
				(width 0.1)
				(type default)
			)
			(layer "F.Fab")
		)
		(fp_line
			(start 0.120396 0.3048)
			(end 0.120396 0.2794)
			(stroke
				(width 0.1)
				(type default)
			)
			(layer "F.Fab")
		)
		(fp_line
			(start 0.12065 -0.3048)
			(end 0.67945 -0.3048)
			(stroke
				(width 0.1)
				(type default)
			)
			(layer "F.Fab")
		)
		(fp_line
			(start 0.12065 -0.2794)
			(end 0.12065 -0.3048)
			(stroke
				(width 0.1)
				(type default)
			)
			(layer "F.Fab")
		)
		(fp_line
			(start 0.67945 -0.3048)
			(end 0.67945 0.3048)
			(stroke
				(width 0.1)
				(type default)
			)
			(layer "F.Fab")
		)
		(fp_line
			(start 0.67945 0.3048)
			(end 0.120396 0.3048)
			(stroke
				(width 0.1)
				(type default)
			)
			(layer "F.Fab")
		)
		(pad "1" smd circle
			(at -0.40005 0)
			(size 0 0)
			(layers "F.Cu" "F.Mask" "F.Paste")
			(net "P3V3_AUX")
		)
		(pad "2" smd circle
			(at 0.40005 0)
			(size 0 0)
			(layers "F.Cu" "F.Mask" "F.Paste")
			(net "FM_LT_KEY_DOWNGRADE_N")
		)
	)
	(footprint ""
		(layer "F.Cu")
		(at 68.147438 -32.776922 90)
		(property "Reference" "PR3847"
			(at 0 0 90)
			(layer "F.SilkS")
			(hide yes)
			(effects
				(font
					(size 1.27 1.27)
				)
			)
		)
		(property "Value" ""
			(at 0 0 90)
			(layer "F.Fab")
			(effects
				(font
					(size 1.27 1.27)
				)
			)
		)
		(duplicate_pad_numbers_are_jumpers no)
		(fp_line
			(start 0.7874 -0.4064)
			(end 0.7874 0.4064)
			(stroke
				(width 0.1524)
				(type default)
			)
			(layer "F.SilkS")
		)
		(fp_line
			(start -0.7874 -0.4064)
			(end 0.7874 -0.4064)
			(stroke
				(width 0.1524)
				(type default)
			)
			(layer "F.SilkS")
		)
		(fp_line
			(start 0.7874 0.4064)
			(end -0.7874 0.4064)
			(stroke
				(width 0.1524)
				(type default)
			)
			(layer "F.SilkS")
		)
		(fp_line
			(start -0.7874 0.4064)
			(end -0.7874 -0.4064)
			(stroke
				(width 0.1524)
				(type default)
			)
			(layer "F.SilkS")
		)
		(fp_line
			(start -0.12065 -0.305054)
			(end -0.12065 -0.2794)
			(stroke
				(width 0.1)
				(type default)
			)
			(layer "F.Fab")
		)
		(fp_line
			(start -0.67945 -0.305054)
			(end -0.12065 -0.305054)
			(stroke
				(width 0.1)
				(type default)
			)
			(layer "F.Fab")
		)
		(fp_line
			(start 0.67945 -0.3048)
			(end 0.67945 0.3048)
			(stroke
				(width 0.1)
				(type default)
			)
			(layer "F.Fab")
		)
		(fp_line
			(start 0.12065 -0.3048)
			(end 0.67945 -0.3048)
			(stroke
				(width 0.1)
				(type default)
			)
			(layer "F.Fab")
		)
		(fp_line
			(start 0.12065 -0.2794)
			(end 0.12065 -0.3048)
			(stroke
				(width 0.1)
				(type default)
			)
			(layer "F.Fab")
		)
		(fp_line
			(start -0.12065 -0.2794)
			(end 0.12065 -0.2794)
			(stroke
				(width 0.1)
				(type default)
			)
			(layer "F.Fab")
		)
		(fp_line
			(start 0.120396 0.2794)
			(end -0.12065 0.2794)
			(stroke
				(width 0.1)
				(type default)
			)
			(layer "F.Fab")
		)
		(fp_line
			(start -0.12065 0.2794)
			(end -0.12065 0.3048)
			(stroke
				(width 0.1)
				(type default)
			)
			(layer "F.Fab")
		)
		(fp_line
			(start 0.67945 0.3048)
			(end 0.120396 0.3048)
			(stroke
				(width 0.1)
				(type default)
			)
			(layer "F.Fab")
		)
		(fp_line
			(start 0.120396 0.3048)
			(end 0.120396 0.2794)
			(stroke
				(width 0.1)
				(type default)
			)
			(layer "F.Fab")
		)
		(fp_line
			(start -0.12065 0.3048)
			(end -0.67945 0.3048)
			(stroke
				(width 0.1)
				(type default)
			)
			(layer "F.Fab")
		)
		(fp_line
			(start -0.67945 0.3048)
			(end -0.67945 -0.305054)
			(stroke
				(width 0.1)
				(type default)
			)
			(layer "F.Fab")
		)
		(pad "1" smd circle
			(at -0.40005 0 90)
			(size 0 0)
			(layers "F.Cu" "F.Mask" "F.Paste")
			(net "P12V_OCP_ISET_2")
		)
		(pad "2" smd circle
			(at 0.40005 0 90)
			(size 0 0)
			(layers "F.Cu" "F.Mask" "F.Paste")
			(net "GND")
		)
	)
)
